# BASEBOARD_FAB2 (Tioga Pass) — schematic netlist excerpt (pin names and nets, part order shuffled) for the footprints in the layout excerpt that follows; sources: Cadence DE-HDL packaged netlist, KiCad conversion of Wiwynn_Tioga_Pass_MB.brd

J6B1  SCONN120_H61426002  CONN  pkg SM  page 194
  IOA1  = P12V_STBY
  IOA2  = P12V_STBY
  IOA3  = P12V_STBY
  IOA4  = P12V_STBY
  IOA5  = P12V_STBY
  IOA6  = P12V_STBY
  IOA7  = P12V_STBY
  IOA8  = P12V_STBY
  IOA9  = GND
  IOA10  = GND
  IOA11  = P3V3_STBY
  IOA12  = GND
  IOA13  = P5V_STBY
  IOA14  = GND
  IOA15  = FM_P1V8MCP_CPU0_EN
  IOA16  = FM_PVCCIOMCP_CPU0_EN
  IOA17  = GND
  IOA18  = SMB_VR_STBY_LVC3_SCL
  IOA19  = SVID_ALERT0_CPU0_R_N
  IOA20  = SVID_CLK0_CPU0_R
  IOB1  = P12V_STBY
  IOB2  = P12V_STBY
  IOB3  = P12V_STBY
  IOB4  = P12V_STBY
  IOB5  = P12V_STBY
  IOB6  = P12V_STBY
  IOB7  = P12V_STBY
  IOB8  = P12V_STBY
  IOB9  = GND
  IOB10  = GND
  IOB11  = P3V3_STBY
  IOB12  = GND
  IOB13  = P5V_STBY
  IOB14  = GND
  IOB15  = PWRGD_P1V8MCP_CPU0
  IOB16  = PWRGD_PVCCIOMCP_CPU0
  IOB17  = GND
  IOB18  = SMB_VR_STBY_LVC3_SDA
  IOB19  = SVID_ALERT1_CPU0_R_N
  IOB20  = SVID_DIO0_CPU0_R
  IOC1  = GND
  IOC2  = GND
  IOC3  = GND
  IOC4  = GND
  IOC5  = GND
  IOC6  = GND
  IOC7  = GND
  IOC8  = GND
  IOC9  = GND
  IOC10  = GND
  IOC11  = P3V3_STBY
  IOC12  = GND
  IOC13  = P5V_STBY
  IOC14  = GND
  IOC15  = GND
  IOC16  = GND
  IOC17  = PVCCIOMCP_CPU0
  IOC18  = PVCCIOMCP_CPU0
  IOC19  = PVCCIOMCP_CPU0
  IOC20  = FM_PVCCMCP_CPU0_EN
  IOD1  = P3V3
  IOD2  = GND
  IOD3  = GND
  IOD4  = GND
  IOD5  = GND
  IOD6  = GND
  IOD7  = GND
  IOD8  = GND
  IOD9  = GND
  IOD10  = GND
  IOD11  = GND
  IOD12  = GND
  IOD13  = GND
  IOD14  = GND
  IOD15  = GND
  IOD16  = GND
  IOD17  = PVCCIOMCP_CPU0
  IOD18  = PVCCIOMCP_CPU0
  IOD19  = PVCCIOMCP_CPU0
  IOD20  = PWRGD_PVCCMCP_CPU0
  IOE1  = FM_CPU0_VRM_322M_156M_OSC_EN
  IOE2  = GND
  IOE3  = GND
  IOE4  = GND
  IOE5  = GND
  IOE6  = GND
  IOE7  = GND
  IOE8  = VSENSE_PVCCIOMCP_CPU0_SKT_VSEN
  IOE9  = GND
  IOE10  = VR_PVCCIOMCP_CPU0_XADDR1
  IOE11  = GND
  IOE12  = GND
  IOE13  = GND
  IOE14  = GND
  IOE15  = PVCCIOMCP_CPU0
  IOE16  = PVCCIOMCP_CPU0
  IOE17  = PVCCIOMCP_CPU0
  IOE18  = PVCCIOMCP_CPU0
  IOE19  = PVCCIOMCP_CPU0
  IOE20  = SVID_CLK1_CPU0_R
  IOF1  = PVCCIO_CPU0
  IOF2  = GND
  IOF3  = GND
  IOF4  = GND
  IOF5  = GND
  IOF6  = GND
  IOF7  = GND
  IOF8  = VSENSE_PVCCIOMCP_CPU0_SKT_VRTN
  IOF9  = GND
  IOF10  = VR_PVCCMCP_CPU0_XADDR2
  IOF11  = GND
  IOF12  = GND
  IOF13  = GND
  IOF14  = GND
  IOF15  = PVCCIOMCP_CPU0
  IOF16  = PVCCIOMCP_CPU0
  IOF17  = PVCCIOMCP_CPU0
  IOF18  = PVCCIOMCP_CPU0
  IOF19  = PVCCIOMCP_CPU0
  IOF20  = SVID_DIO1_CPU0_R

(kicad_pcb
	(version 20260206)
	(generator "pcbnew")
	(generator_version "10.0")
	(general
		(thickness 1.6)
		(legacy_teardrops no)
	)
	(paper "A4")
	(title_block
		(title "Wiwynn_Tioga_Pass_MB.brd")
		(comment 1 "Tioga Pass / footprint 1366 of 4770 (J6B1), pads 52-102 of 122")
	)
	(layers
		(0 "F.Cu" signal "TOP")
		(4 "In1.Cu" signal "L2GND")
		(6 "In2.Cu" signal "L3")
		(8 "In3.Cu" signal "L4GND")
		(10 "In4.Cu" signal "L5")
		(12 "In5.Cu" signal "L6GND")
		(14 "In6.Cu" signal "L7VCC")
		(16 "In7.Cu" signal "L8VCC")
		(18 "In8.Cu" signal "L9GND")
		(20 "In9.Cu" signal "L10")
		(22 "In10.Cu" signal "L11GND")
		(24 "In11.Cu" signal "L12")
		(26 "In12.Cu" signal "L13GND")
		(2 "B.Cu" signal "BOTTOM")
		(9 "F.Adhes" user "F.Adhesive")
		(11 "B.Adhes" user "B.Adhesive")
		(13 "F.Paste" user "Package Geometry/Pastemask Top")
		(15 "B.Paste" user "Package Geometry/Pastemask Bottom")
		(5 "F.SilkS" user "Ref Des/Silkscreen Top")
		(7 "B.SilkS" user "Ref Des/Silkscreen Bottom")
		(1 "F.Mask" user "Board Geometry/Soldermask Top")
		(3 "B.Mask" user "Board Geometry/Soldermask Bottom")
		(17 "Dwgs.User" user "User.Drawings")
		(19 "Cmts.User" user "User.Comments")
		(21 "Eco1.User" user "User.Eco1")
		(23 "Eco2.User" user "User.Eco2")
		(25 "Edge.Cuts" user "Board Geometry/Outline")
		(27 "Margin" user)
		(31 "F.CrtYd" user "Package Geometry/Place Bound Top")
		(29 "B.CrtYd" user "Package Geometry/Place Bound Bottom")
		(35 "F.Fab" user "Ref Des/Assembly Top")
		(33 "B.Fab" user "Ref Des/Assembly Bottom")
	)
	(footprint ""
		(layer "F.Cu")
		(at 329.594972 -115.55095 90)
		(property "Reference" "J6B1"
			(at -3.59283 -5.018024 90)
			(unlocked yes)
			(layer "F.SilkS")
			(effects
				(font
					(size 0.7874 0.5842)
					(thickness 0.1524)
				)
			)
		)
		(property "Value" ""
			(at 0 0 90)
			(layer "F.Fab")
			(effects
				(font
					(size 1.27 1.27)
				)
			)
		)
		(duplicate_pad_numbers_are_jumpers no)
		(pad "C10" smd circle
			(at -2.54 11.43 90)
			(size 0.635 0.635)
			(layers "F.Cu" "F.Mask" "F.Paste")
			(net "GND")
		)
		(pad "C11" smd circle
			(at -2.54 12.7 90)
			(size 0.635 0.635)
			(layers "F.Cu" "F.Mask" "F.Paste")
			(net "P3V3_STBY")
		)
		(pad "C12" smd circle
			(at -2.54 13.97 90)
			(size 0.635 0.635)
			(layers "F.Cu" "F.Mask" "F.Paste")
			(net "GND")
		)
		(pad "C13" smd circle
			(at -2.54 15.24 90)
			(size 0.635 0.635)
			(layers "F.Cu" "F.Mask" "F.Paste")
			(net "P5V_STBY")
		)
		(pad "C14" smd circle
			(at -2.54 16.51 90)
			(size 0.635 0.635)
			(layers "F.Cu" "F.Mask" "F.Paste")
			(net "GND")
		)
		(pad "C15" smd circle
			(at -2.54 17.78 90)
			(size 0.635 0.635)
			(layers "F.Cu" "F.Mask" "F.Paste")
			(net "GND")
		)
		(pad "C16" smd circle
			(at -2.54 19.05 90)
			(size 0.635 0.635)
			(layers "F.Cu" "F.Mask" "F.Paste")
			(net "GND")
		)
		(pad "C17" smd circle
			(at -2.54 20.32 90)
			(size 0.635 0.635)
			(layers "F.Cu" "F.Mask" "F.Paste")
			(net "PVCCIOMCP_CPU0")
		)
		(pad "C18" smd circle
			(at -2.54 21.59 90)
			(size 0.635 0.635)
			(layers "F.Cu" "F.Mask" "F.Paste")
			(net "PVCCIOMCP_CPU0")
		)
		(pad "C19" smd circle
			(at -2.54 22.86 90)
			(size 0.635 0.635)
			(layers "F.Cu" "F.Mask" "F.Paste")
			(net "PVCCIOMCP_CPU0")
		)
		(pad "C20" smd circle
			(at -2.54 24.13 90)
			(size 0.635 0.635)
			(layers "F.Cu" "F.Mask" "F.Paste")
			(net "FM_PVCCMCP_CPU0_EN")
		)
		(pad "D1" smd circle
			(at -3.81 0 90)
			(size 0.635 0.635)
			(layers "F.Cu" "F.Mask" "F.Paste")
			(net "P3V3")
		)
		(pad "D2" smd circle
			(at -3.81 1.27 90)
			(size 0.635 0.635)
			(layers "F.Cu" "F.Mask" "F.Paste")
			(net "GND")
		)
		(pad "D3" smd circle
			(at -3.81 2.54 90)
			(size 0.635 0.635)
			(layers "F.Cu" "F.Mask" "F.Paste")
			(net "GND")
		)
		(pad "D4" smd circle
			(at -3.81 3.81 90)
			(size 0.635 0.635)
			(layers "F.Cu" "F.Mask" "F.Paste")
			(net "GND")
		)
		(pad "D5" smd circle
			(at -3.81 5.08 90)
			(size 0.635 0.635)
			(layers "F.Cu" "F.Mask" "F.Paste")
			(net "GND")
		)
		(pad "D6" smd circle
			(at -3.81 6.35 90)
			(size 0.635 0.635)
			(layers "F.Cu" "F.Mask" "F.Paste")
			(net "GND")
		)
		(pad "D7" smd circle
			(at -3.81 7.62 90)
			(size 0.635 0.635)
			(layers "F.Cu" "F.Mask" "F.Paste")
			(net "GND")
		)
		(pad "D8" smd circle
			(at -3.81 8.89 90)
			(size 0.635 0.635)
			(layers "F.Cu" "F.Mask" "F.Paste")
			(net "GND")
		)
		(pad "D9" smd circle
			(at -3.81 10.16 90)
			(size 0.635 0.635)
			(layers "F.Cu" "F.Mask" "F.Paste")
			(net "GND")
		)
		(pad "D10" smd circle
			(at -3.81 11.43 90)
			(size 0.635 0.635)
			(layers "F.Cu" "F.Mask" "F.Paste")
			(net "GND")
		)
		(pad "D11" smd circle
			(at -3.81 12.7 90)
			(size 0.635 0.635)
			(layers "F.Cu" "F.Mask" "F.Paste")
			(net "GND")
		)
		(pad "D12" smd circle
			(at -3.81 13.97 90)
			(size 0.635 0.635)
			(layers "F.Cu" "F.Mask" "F.Paste")
			(net "GND")
		)
		(pad "D13" smd circle
			(at -3.81 15.24 90)
			(size 0.635 0.635)
			(layers "F.Cu" "F.Mask" "F.Paste")
			(net "GND")
		)
		(pad "D14" smd circle
			(at -3.81 16.51 90)
			(size 0.635 0.635)
			(layers "F.Cu" "F.Mask" "F.Paste")
			(net "GND")
		)
		(pad "D15" smd circle
			(at -3.81 17.78 90)
			(size 0.635 0.635)
			(layers "F.Cu" "F.Mask" "F.Paste")
			(net "GND")
		)
		(pad "D16" smd circle
			(at -3.81 19.05 90)
			(size 0.635 0.635)
			(layers "F.Cu" "F.Mask" "F.Paste")
			(net "GND")
		)
		(pad "D17" smd circle
			(at -3.81 20.32 90)
			(size 0.635 0.635)
			(layers "F.Cu" "F.Mask" "F.Paste")
			(net "PVCCIOMCP_CPU0")
		)
		(pad "D18" smd circle
			(at -3.81 21.59 90)
			(size 0.635 0.635)
			(layers "F.Cu" "F.Mask" "F.Paste")
			(net "PVCCIOMCP_CPU0")
		)
		(pad "D19" smd circle
			(at -3.81 22.86 90)
			(size 0.635 0.635)
			(layers "F.Cu" "F.Mask" "F.Paste")
			(net "PVCCIOMCP_CPU0")
		)
		(pad "D20" smd circle
			(at -3.81 24.13 90)
			(size 0.635 0.635)
			(layers "F.Cu" "F.Mask" "F.Paste")
			(net "PWRGD_PVCCMCP_CPU0")
		)
		(pad "E1" smd circle
			(at -5.08 0 90)
			(size 0.635 0.635)
			(layers "F.Cu" "F.Mask" "F.Paste")
			(net "FM_CPU0_VRM_322M_156M_OSC_EN")
		)
		(pad "E2" smd circle
			(at -5.08 1.27 90)
			(size 0.635 0.635)
			(layers "F.Cu" "F.Mask" "F.Paste")
			(net "GND")
		)
		(pad "E3" smd circle
			(at -5.08 2.54 90)
			(size 0.635 0.635)
			(layers "F.Cu" "F.Mask" "F.Paste")
			(net "GND")
		)
		(pad "E4" smd circle
			(at -5.08 3.81 90)
			(size 0.635 0.635)
			(layers "F.Cu" "F.Mask" "F.Paste")
			(net "GND")
		)
		(pad "E5" smd circle
			(at -5.08 5.08 90)
			(size 0.635 0.635)
			(layers "F.Cu" "F.Mask" "F.Paste")
			(net "GND")
		)
		(pad "E6" smd circle
			(at -5.08 6.35 90)
			(size 0.635 0.635)
			(layers "F.Cu" "F.Mask" "F.Paste")
			(net "GND")
		)
		(pad "E7" smd circle
			(at -5.08 7.62 90)
			(size 0.635 0.635)
			(layers "F.Cu" "F.Mask" "F.Paste")
			(net "GND")
		)
		(pad "E8" smd circle
			(at -5.08 8.89 90)
			(size 0.635 0.635)
			(layers "F.Cu" "F.Mask" "F.Paste")
			(net "VSENSE_PVCCIOMCP_CPU0_SKT_VSEN")
		)
		(pad "E9" smd circle
			(at -5.08 10.16 90)
			(size 0.635 0.635)
			(layers "F.Cu" "F.Mask" "F.Paste")
			(net "GND")
		)
		(pad "E10" smd circle
			(at -5.08 11.43 90)
			(size 0.635 0.635)
			(layers "F.Cu" "F.Mask" "F.Paste")
			(net "VR_PVCCIOMCP_CPU0_XADDR1")
		)
		(pad "E11" smd circle
			(at -5.08 12.7 90)
			(size 0.635 0.635)
			(layers "F.Cu" "F.Mask" "F.Paste")
			(net "GND")
		)
		(pad "E12" smd circle
			(at -5.08 13.97 90)
			(size 0.635 0.635)
			(layers "F.Cu" "F.Mask" "F.Paste")
			(net "GND")
		)
		(pad "E13" smd circle
			(at -5.08 15.24 90)
			(size 0.635 0.635)
			(layers "F.Cu" "F.Mask" "F.Paste")
			(net "GND")
		)
		(pad "E14" smd circle
			(at -5.08 16.51 90)
			(size 0.635 0.635)
			(layers "F.Cu" "F.Mask" "F.Paste")
			(net "GND")
		)
		(pad "E15" smd circle
			(at -5.08 17.78 90)
			(size 0.635 0.635)
			(layers "F.Cu" "F.Mask" "F.Paste")
			(net "PVCCIOMCP_CPU0")
		)
		(pad "E16" smd circle
			(at -5.08 19.05 90)
			(size 0.635 0.635)
			(layers "F.Cu" "F.Mask" "F.Paste")
			(net "PVCCIOMCP_CPU0")
		)
		(pad "E17" smd circle
			(at -5.08 20.32 90)
			(size 0.635 0.635)
			(layers "F.Cu" "F.Mask" "F.Paste")
			(net "PVCCIOMCP_CPU0")
		)
		(pad "E18" smd circle
			(at -5.08 21.59 90)
			(size 0.635 0.635)
			(layers "F.Cu" "F.Mask" "F.Paste")
			(net "PVCCIOMCP_CPU0")
		)
		(pad "E19" smd circle
			(at -5.08 22.86 90)
			(size 0.635 0.635)
			(layers "F.Cu" "F.Mask" "F.Paste")
			(net "PVCCIOMCP_CPU0")
		)
		(pad "E20" smd circle
			(at -5.08 24.13 90)
			(size 0.635 0.635)
			(layers "F.Cu" "F.Mask" "F.Paste")
			(net "SVID_CLK1_CPU0_R")
		)
	)
)
